# T6G (Grand Teton) — schematic netlist excerpt (pin names and nets, part order shuffled) for the footprints in the layout excerpt that follows; sources: Cadence DE-HDL packaged netlist, KiCad conversion of 04192023_DAF0TMB3IC0_F0TG_MB_C_brd_V02_OCP.brd

R6858  Q_RES  0 5% CHIP  pkg 0402LF  page 151 : A = SMB_VR_3V3STBY_SCL ; B = P0V9_RETIMER_CPU1_PMSCL
C566  Q_CAP  0.1UF 10V 10% X7S  pkg C0201  page 279 : A = P0V9_CPU0_RT0_2A ; B = GND
C2209  Q_CAP  22UF 4V 20% X6S  pkg C0402  page 69 : A = PVDDCR_CPU1_P0 ; B = GND

(kicad_pcb
	(version 20260206)
	(generator "pcbnew")
	(generator_version "10.0")
	(general
		(thickness 1.6)
		(legacy_teardrops no)
	)
	(paper "A4")
	(title_block
		(title "04192023_DAF0TMB3IC0_F0TG_MB_C_brd_V02_OCP.brd")
		(comment 1 "Grand Teton / footprints 6729-6731 of 8354")
	)
	(layers
		(0 "F.Cu" signal "TOP")
		(4 "In1.Cu" signal "GND")
		(6 "In2.Cu" signal "IN1")
		(8 "In3.Cu" signal "GND1")
		(10 "In4.Cu" signal "IN2")
		(12 "In5.Cu" signal "GND2")
		(14 "In6.Cu" signal "IN3")
		(16 "In7.Cu" signal "GND3")
		(18 "In8.Cu" signal "VCC")
		(20 "In9.Cu" signal "VCC1")
		(22 "In10.Cu" signal "GND4")
		(24 "In11.Cu" signal "IN4")
		(26 "In12.Cu" signal "GND5")
		(28 "In13.Cu" signal "IN5")
		(30 "In14.Cu" signal "GND6")
		(32 "In15.Cu" signal "IN6")
		(34 "In16.Cu" signal "GND7")
		(2 "B.Cu" signal "BOTTOM")
		(9 "F.Adhes" user "F.Adhesive")
		(11 "B.Adhes" user "B.Adhesive")
		(13 "F.Paste" user "Package Geometry/Pastemask Top")
		(15 "B.Paste" user "Package Geometry/Pastemask Bottom")
		(5 "F.SilkS" user "Ref Des/Silkscreen Top")
		(7 "B.SilkS" user "Ref Des/Silkscreen Bottom")
		(1 "F.Mask" user "Board Geometry/Soldermask Top")
		(3 "B.Mask" user "Board Geometry/Soldermask Bottom")
		(17 "Dwgs.User" user "User.Drawings")
		(19 "Cmts.User" user "User.Comments")
		(21 "Eco1.User" user "User.Eco1")
		(23 "Eco2.User" user "User.Eco2")
		(25 "Edge.Cuts" user "Board Geometry/Outline")
		(27 "Margin" user)
		(31 "F.CrtYd" user "Package Geometry/Place Bound Top")
		(29 "B.CrtYd" user "Package Geometry/Place Bound Bottom")
		(35 "F.Fab" user "Ref Des/Assembly Top")
		(33 "B.Fab" user "Ref Des/Assembly Bottom")
	)
	(footprint ""
		(layer "B.Cu")
		(at 323.417184 -396.150592 180)
		(property "Reference" "C566"
			(at 0 0 0)
			(layer "B.SilkS")
			(hide yes)
			(effects
				(font
					(size 1.27 1.27)
				)
				(justify mirror)
			)
		)
		(property "Value" ""
			(at 0 0 0)
			(layer "B.Fab")
			(effects
				(font
					(size 1.27 1.27)
				)
				(justify mirror)
			)
		)
		(duplicate_pad_numbers_are_jumpers no)
		(fp_line
			(start 0.299974 0.150114)
			(end 0.299974 -0.150114)
			(stroke
				(width 0.1)
				(type default)
			)
			(layer "B.Fab")
		)
		(fp_line
			(start 0.299974 -0.150114)
			(end -0.299974 -0.150114)
			(stroke
				(width 0.1)
				(type default)
			)
			(layer "B.Fab")
		)
		(fp_line
			(start -0.299974 0.150114)
			(end 0.299974 0.150114)
			(stroke
				(width 0.1)
				(type default)
			)
			(layer "B.Fab")
		)
		(fp_line
			(start -0.299974 -0.150114)
			(end -0.299974 0.150114)
			(stroke
				(width 0.1)
				(type default)
			)
			(layer "B.Fab")
		)
		(pad "1" smd rect
			(at 0.2667 0)
			(size 0.3048 0.381)
			(layers "B.Cu" "B.Mask" "B.Paste")
			(net "P0V9_CPU0_RT0_2A")
		)
		(pad "2" smd rect
			(at -0.2667 0)
			(size 0.3048 0.381)
			(layers "B.Cu" "B.Mask" "B.Paste")
			(net "GND")
		)
	)
	(footprint ""
		(layer "B.Cu")
		(at 13.65885 -403.855174 180)
		(property "Reference" "R6858"
			(at 0 0 0)
			(layer "B.SilkS")
			(hide yes)
			(effects
				(font
					(size 1.27 1.27)
				)
				(justify mirror)
			)
		)
		(property "Value" ""
			(at 0 0 0)
			(layer "B.Fab")
			(effects
				(font
					(size 1.27 1.27)
				)
				(justify mirror)
			)
		)
		(duplicate_pad_numbers_are_jumpers no)
		(fp_line
			(start 0.7874 0.4064)
			(end 0.7874 -0.4064)
			(stroke
				(width 0.1524)
				(type default)
			)
			(layer "B.SilkS")
		)
		(fp_line
			(start 0.7874 -0.4064)
			(end -0.7874 -0.4064)
			(stroke
				(width 0.1524)
				(type default)
			)
			(layer "B.SilkS")
		)
		(fp_line
			(start -0.7874 0.4064)
			(end 0.7874 0.4064)
			(stroke
				(width 0.1524)
				(type default)
			)
			(layer "B.SilkS")
		)
		(fp_line
			(start -0.7874 -0.4064)
			(end -0.7874 0.4064)
			(stroke
				(width 0.1524)
				(type default)
			)
			(layer "B.SilkS")
		)
		(fp_line
			(start 0.67945 0.3048)
			(end 0.67945 -0.305054)
			(stroke
				(width 0.1)
				(type default)
			)
			(layer "B.Fab")
		)
		(fp_line
			(start 0.67945 -0.305054)
			(end 0.12065 -0.305054)
			(stroke
				(width 0.1)
				(type default)
			)
			(layer "B.Fab")
		)
		(fp_line
			(start 0.12065 0.3048)
			(end 0.67945 0.3048)
			(stroke
				(width 0.1)
				(type default)
			)
			(layer "B.Fab")
		)
		(fp_line
			(start 0.12065 0.2794)
			(end 0.12065 0.3048)
			(stroke
				(width 0.1)
				(type default)
			)
			(layer "B.Fab")
		)
		(fp_line
			(start 0.12065 -0.2794)
			(end -0.12065 -0.2794)
			(stroke
				(width 0.1)
				(type default)
			)
			(layer "B.Fab")
		)
		(fp_line
			(start 0.12065 -0.305054)
			(end 0.12065 -0.2794)
			(stroke
				(width 0.1)
				(type default)
			)
			(layer "B.Fab")
		)
		(fp_line
			(start -0.120396 0.3048)
			(end -0.120396 0.2794)
			(stroke
				(width 0.1)
				(type default)
			)
			(layer "B.Fab")
		)
		(fp_line
			(start -0.120396 0.2794)
			(end 0.12065 0.2794)
			(stroke
				(width 0.1)
				(type default)
			)
			(layer "B.Fab")
		)
		(fp_line
			(start -0.12065 -0.2794)
			(end -0.12065 -0.3048)
			(stroke
				(width 0.1)
				(type default)
			)
			(layer "B.Fab")
		)
		(fp_line
			(start -0.12065 -0.3048)
			(end -0.67945 -0.3048)
			(stroke
				(width 0.1)
				(type default)
			)
			(layer "B.Fab")
		)
		(fp_line
			(start -0.67945 0.3048)
			(end -0.120396 0.3048)
			(stroke
				(width 0.1)
				(type default)
			)
			(layer "B.Fab")
		)
		(fp_line
			(start -0.67945 -0.3048)
			(end -0.67945 0.3048)
			(stroke
				(width 0.1)
				(type default)
			)
			(layer "B.Fab")
		)
		(pad "1" smd circle
			(at 0.40005 0)
			(size 0 0)
			(layers "B.Cu" "B.Mask" "B.Paste")
			(net "SMB_VR_3V3STBY_SCL")
		)
		(pad "2" smd circle
			(at -0.40005 0)
			(size 0 0)
			(layers "B.Cu" "B.Mask" "B.Paste")
			(net "P0V9_RETIMER_CPU1_PMSCL")
		)
	)
	(footprint ""
		(layer "B.Cu")
		(at 356.711758 -271.395952)
		(property "Reference" "C2209"
			(at 0 0 0)
			(layer "B.SilkS")
			(hide yes)
			(effects
				(font
					(size 1.27 1.27)
				)
				(justify mirror)
			)
		)
		(property "Value" ""
			(at 0 0 0)
			(layer "B.Fab")
			(effects
				(font
					(size 1.27 1.27)
				)
				(justify mirror)
			)
		)
		(duplicate_pad_numbers_are_jumpers no)
		(fp_line
			(start -0.7874 -0.4064)
			(end -0.7874 0.4064)
			(stroke
				(width 0.1524)
				(type default)
			)
			(layer "B.SilkS")
		)
		(fp_line
			(start -0.7874 0.4064)
			(end 0.7874 0.4064)
			(stroke
				(width 0.1524)
				(type default)
			)
			(layer "B.SilkS")
		)
		(fp_line
			(start 0.7874 -0.4064)
			(end -0.7874 -0.4064)
			(stroke
				(width 0.1524)
				(type default)
			)
			(layer "B.SilkS")
		)
		(fp_line
			(start 0.7874 0.4064)
			(end 0.7874 -0.4064)
			(stroke
				(width 0.1524)
				(type default)
			)
			(layer "B.SilkS")
		)
		(fp_line
			(start -0.67945 -0.3048)
			(end -0.67945 0.3048)
			(stroke
				(width 0.1)
				(type default)
			)
			(layer "B.Fab")
		)
		(fp_line
			(start -0.67945 0.3048)
			(end -0.120396 0.3048)
			(stroke
				(width 0.1)
				(type default)
			)
			(layer "B.Fab")
		)
		(fp_line
			(start -0.12065 -0.3048)
			(end -0.67945 -0.3048)
			(stroke
				(width 0.1)
				(type default)
			)
			(layer "B.Fab")
		)
		(fp_line
			(start -0.12065 -0.2794)
			(end -0.12065 -0.3048)
			(stroke
				(width 0.1)
				(type default)
			)
			(layer "B.Fab")
		)
		(fp_line
			(start -0.120396 0.2794)
			(end 0.12065 0.2794)
			(stroke
				(width 0.1)
				(type default)
			)
			(layer "B.Fab")
		)
		(fp_line
			(start -0.120396 0.3048)
			(end -0.120396 0.2794)
			(stroke
				(width 0.1)
				(type default)
			)
			(layer "B.Fab")
		)
		(fp_line
			(start 0.12065 -0.305054)
			(end 0.12065 -0.2794)
			(stroke
				(width 0.1)
				(type default)
			)
			(layer "B.Fab")
		)
		(fp_line
			(start 0.12065 -0.2794)
			(end -0.12065 -0.2794)
			(stroke
				(width 0.1)
				(type default)
			)
			(layer "B.Fab")
		)
		(fp_line
			(start 0.12065 0.2794)
			(end 0.12065 0.3048)
			(stroke
				(width 0.1)
				(type default)
			)
			(layer "B.Fab")
		)
		(fp_line
			(start 0.12065 0.3048)
			(end 0.67945 0.3048)
			(stroke
				(width 0.1)
				(type default)
			)
			(layer "B.Fab")
		)
		(fp_line
			(start 0.67945 -0.305054)
			(end 0.12065 -0.305054)
			(stroke
				(width 0.1)
				(type default)
			)
			(layer "B.Fab")
		)
		(fp_line
			(start 0.67945 0.3048)
			(end 0.67945 -0.305054)
			(stroke
				(width 0.1)
				(type default)
			)
			(layer "B.Fab")
		)
		(pad "1" smd circle
			(at 0.40005 0 180)
			(size 0 0)
			(layers "B.Cu" "B.Mask" "B.Paste")
			(net "PVDDCR_CPU1_P0")
		)
		(pad "2" smd circle
			(at -0.40005 0 180)
			(size 0 0)
			(layers "B.Cu" "B.Mask" "B.Paste")
			(net "GND")
		)
	)
)
